# S9S_MB_2U (Grand Teton) — schematic netlist excerpt (pin names and nets, part order shuffled) for the footprints in the layout excerpt that follows; sources: Cadence DE-HDL packaged netlist, KiCad conversion of 03242023_DA0F0TMBIJ0_F0T_Motherboard_J_brd_V01_OCP.brd

R4599  Q_RES  0 5% CHIP  pkg 0402LF  page 214 : A = HP_LVC3_OCP_V3_2_P12V_PWRGD ; B = HP_LVC3_OCP_V3_2_HSC_PWRGD_PLD_
C1562  Q_CAP  1UF 25V 10% EMPTY  pkg C0402  page 306 : A = U205_VDD ; B = GND

(kicad_pcb
	(version 20260206)
	(generator "pcbnew")
	(generator_version "10.0")
	(general
		(thickness 1.6)
		(legacy_teardrops no)
	)
	(paper "A4")
	(title_block
		(title "03242023_DA0F0TMBIJ0_F0T_Motherboard_J_brd_V01_OCP.brd")
		(comment 1 "Grand Teton / footprints 1742-1743 of 6105")
	)
	(layers
		(0 "F.Cu" signal "TOP")
		(4 "In1.Cu" signal "GND")
		(6 "In2.Cu" signal "IN1")
		(8 "In3.Cu" signal "GND1")
		(10 "In4.Cu" signal "IN2")
		(12 "In5.Cu" signal "GND2")
		(14 "In6.Cu" signal "IN3")
		(16 "In7.Cu" signal "GND3")
		(18 "In8.Cu" signal "VCC")
		(20 "In9.Cu" signal "VCC1")
		(22 "In10.Cu" signal "GND4")
		(24 "In11.Cu" signal "IN4")
		(26 "In12.Cu" signal "GND5")
		(28 "In13.Cu" signal "IN5")
		(30 "In14.Cu" signal "GND6")
		(32 "In15.Cu" signal "IN6")
		(34 "In16.Cu" signal "GND7")
		(2 "B.Cu" signal "BOTTOM")
		(9 "F.Adhes" user "F.Adhesive")
		(11 "B.Adhes" user "B.Adhesive")
		(13 "F.Paste" user "Package Geometry/Pastemask Top")
		(15 "B.Paste" user "Package Geometry/Pastemask Bottom")
		(5 "F.SilkS" user "Ref Des/Silkscreen Top")
		(7 "B.SilkS" user "Ref Des/Silkscreen Bottom")
		(1 "F.Mask" user "Board Geometry/Soldermask Top")
		(3 "B.Mask" user "Board Geometry/Soldermask Bottom")
		(17 "Dwgs.User" user "User.Drawings")
		(19 "Cmts.User" user "User.Comments")
		(21 "Eco1.User" user "User.Eco1")
		(23 "Eco2.User" user "User.Eco2")
		(25 "Edge.Cuts" user "Board Geometry/Outline")
		(27 "Margin" user)
		(31 "F.CrtYd" user "Package Geometry/Place Bound Top")
		(29 "B.CrtYd" user "Package Geometry/Place Bound Bottom")
		(35 "F.Fab" user "Ref Des/Assembly Top")
		(33 "B.Fab" user "Ref Des/Assembly Bottom")
	)
	(footprint ""
		(layer "F.Cu")
		(at 210.560158 -103.95204 180)
		(property "Reference" "C1562"
			(at 0 0 180)
			(layer "F.SilkS")
			(hide yes)
			(effects
				(font
					(size 1.27 1.27)
				)
			)
		)
		(property "Value" ""
			(at 0 0 180)
			(layer "F.Fab")
			(effects
				(font
					(size 1.27 1.27)
				)
			)
		)
		(duplicate_pad_numbers_are_jumpers no)
		(fp_line
			(start 0.7874 0.4064)
			(end -0.7874 0.4064)
			(stroke
				(width 0.1524)
				(type default)
			)
			(layer "F.SilkS")
		)
		(fp_line
			(start 0.7874 -0.4064)
			(end 0.7874 0.4064)
			(stroke
				(width 0.1524)
				(type default)
			)
			(layer "F.SilkS")
		)
		(fp_line
			(start -0.7874 0.4064)
			(end -0.7874 -0.4064)
			(stroke
				(width 0.1524)
				(type default)
			)
			(layer "F.SilkS")
		)
		(fp_line
			(start -0.7874 -0.4064)
			(end 0.7874 -0.4064)
			(stroke
				(width 0.1524)
				(type default)
			)
			(layer "F.SilkS")
		)
		(fp_line
			(start 0.67945 0.3048)
			(end 0.120396 0.3048)
			(stroke
				(width 0.1)
				(type default)
			)
			(layer "F.Fab")
		)
		(fp_line
			(start 0.67945 -0.3048)
			(end 0.67945 0.3048)
			(stroke
				(width 0.1)
				(type default)
			)
			(layer "F.Fab")
		)
		(fp_line
			(start 0.12065 -0.2794)
			(end 0.12065 -0.3048)
			(stroke
				(width 0.1)
				(type default)
			)
			(layer "F.Fab")
		)
		(fp_line
			(start 0.12065 -0.3048)
			(end 0.67945 -0.3048)
			(stroke
				(width 0.1)
				(type default)
			)
			(layer "F.Fab")
		)
		(fp_line
			(start 0.120396 0.3048)
			(end 0.120396 0.2794)
			(stroke
				(width 0.1)
				(type default)
			)
			(layer "F.Fab")
		)
		(fp_line
			(start 0.120396 0.2794)
			(end -0.12065 0.2794)
			(stroke
				(width 0.1)
				(type default)
			)
			(layer "F.Fab")
		)
		(fp_line
			(start -0.12065 0.3048)
			(end -0.67945 0.3048)
			(stroke
				(width 0.1)
				(type default)
			)
			(layer "F.Fab")
		)
		(fp_line
			(start -0.12065 0.2794)
			(end -0.12065 0.3048)
			(stroke
				(width 0.1)
				(type default)
			)
			(layer "F.Fab")
		)
		(fp_line
			(start -0.12065 -0.2794)
			(end 0.12065 -0.2794)
			(stroke
				(width 0.1)
				(type default)
			)
			(layer "F.Fab")
		)
		(fp_line
			(start -0.12065 -0.305054)
			(end -0.12065 -0.2794)
			(stroke
				(width 0.1)
				(type default)
			)
			(layer "F.Fab")
		)
		(fp_line
			(start -0.67945 0.3048)
			(end -0.67945 -0.305054)
			(stroke
				(width 0.1)
				(type default)
			)
			(layer "F.Fab")
		)
		(fp_line
			(start -0.67945 -0.305054)
			(end -0.12065 -0.305054)
			(stroke
				(width 0.1)
				(type default)
			)
			(layer "F.Fab")
		)
		(pad "1" smd circle
			(at -0.40005 0 180)
			(size 0 0)
			(layers "F.Cu" "F.Mask" "F.Paste")
			(net "U205_VDD")
		)
		(pad "2" smd circle
			(at 0.40005 0 180)
			(size 0 0)
			(layers "F.Cu" "F.Mask" "F.Paste")
			(net "GND")
		)
	)
	(footprint ""
		(layer "F.Cu")
		(at 191.284606 -126.968758 -90)
		(property "Reference" "R4599"
			(at 0 0 270)
			(layer "F.SilkS")
			(hide yes)
			(effects
				(font
					(size 1.27 1.27)
				)
			)
		)
		(property "Value" ""
			(at 0 0 270)
			(layer "F.Fab")
			(effects
				(font
					(size 1.27 1.27)
				)
			)
		)
		(duplicate_pad_numbers_are_jumpers no)
		(fp_line
			(start -0.7874 0.4064)
			(end -0.7874 -0.4064)
			(stroke
				(width 0.1524)
				(type default)
			)
			(layer "F.SilkS")
		)
		(fp_line
			(start 0.7874 0.4064)
			(end -0.7874 0.4064)
			(stroke
				(width 0.1524)
				(type default)
			)
			(layer "F.SilkS")
		)
		(fp_line
			(start -0.7874 -0.4064)
			(end 0.7874 -0.4064)
			(stroke
				(width 0.1524)
				(type default)
			)
			(layer "F.SilkS")
		)
		(fp_line
			(start 0.7874 -0.4064)
			(end 0.7874 0.4064)
			(stroke
				(width 0.1524)
				(type default)
			)
			(layer "F.SilkS")
		)
		(fp_line
			(start -0.67945 0.3048)
			(end -0.67945 -0.305054)
			(stroke
				(width 0.1)
				(type default)
			)
			(layer "F.Fab")
		)
		(fp_line
			(start -0.12065 0.3048)
			(end -0.67945 0.3048)
			(stroke
				(width 0.1)
				(type default)
			)
			(layer "F.Fab")
		)
		(fp_line
			(start 0.120396 0.3048)
			(end 0.120396 0.2794)
			(stroke
				(width 0.1)
				(type default)
			)
			(layer "F.Fab")
		)
		(fp_line
			(start 0.67945 0.3048)
			(end 0.120396 0.3048)
			(stroke
				(width 0.1)
				(type default)
			)
			(layer "F.Fab")
		)
		(fp_line
			(start -0.12065 0.2794)
			(end -0.12065 0.3048)
			(stroke
				(width 0.1)
				(type default)
			)
			(layer "F.Fab")
		)
		(fp_line
			(start 0.120396 0.2794)
			(end -0.12065 0.2794)
			(stroke
				(width 0.1)
				(type default)
			)
			(layer "F.Fab")
		)
		(fp_line
			(start -0.12065 -0.2794)
			(end 0.12065 -0.2794)
			(stroke
				(width 0.1)
				(type default)
			)
			(layer "F.Fab")
		)
		(fp_line
			(start 0.12065 -0.2794)
			(end 0.12065 -0.3048)
			(stroke
				(width 0.1)
				(type default)
			)
			(layer "F.Fab")
		)
		(fp_line
			(start 0.12065 -0.3048)
			(end 0.67945 -0.3048)
			(stroke
				(width 0.1)
				(type default)
			)
			(layer "F.Fab")
		)
		(fp_line
			(start 0.67945 -0.3048)
			(end 0.67945 0.3048)
			(stroke
				(width 0.1)
				(type default)
			)
			(layer "F.Fab")
		)
		(fp_line
			(start -0.67945 -0.305054)
			(end -0.12065 -0.305054)
			(stroke
				(width 0.1)
				(type default)
			)
			(layer "F.Fab")
		)
		(fp_line
			(start -0.12065 -0.305054)
			(end -0.12065 -0.2794)
			(stroke
				(width 0.1)
				(type default)
			)
			(layer "F.Fab")
		)
		(pad "1" smd circle
			(at -0.40005 0 270)
			(size 0 0)
			(layers "F.Cu" "F.Mask" "F.Paste")
			(net "HP_LVC3_OCP_V3_2_P12V_PWRGD")
		)
		(pad "2" smd circle
			(at 0.40005 0 270)
			(size 0 0)
			(layers "F.Cu" "F.Mask" "F.Paste")
			(net "HP_LVC3_OCP_V3_2_HSC_PWRGD_PLD_")
		)
	)
)
